FILE_TYPE = CONNECTIVITY;
{Allegro Design Entry HDL 17.4-2019 S026 (4007227) 1/17/2022}
"PAGE_NUMBER" = 29;
0"NC";
1"GND\g";
2"PVDD18_S5_P0\g";
3"ESPI_CPU0_D0";
4"ESPI_CPU0_D1";
5"ESPI_CPU0_D2";
6"CLK_ESPI_CPU0_CLK1";
7"CLK_ESPI_CPU0_R_CLK1";
8"PD_ESPI_CPU0_CLK2";
9"RST_ESPI_CPU0_R_RSTOUT_N";
10"RST_ESPI_CPU0_RSTOUT_N";
11"SPI_CPU0_TPM_CS_N";
12"CPU0_ESPI0_ALERT_N";
13"ESPI_CPU0_R_ALERT_N";
14"ESPI_CPU0_R_D3";
15"ESPI_CPU0_R_D0";
16"ESPI_CPU0_R_D1";
17"ESPI_CPU0_ALERT_P0_N";
18"ESPI_CPU0_ALERT_P0_N";
19"ESPI_CPU0_CS1_N";
20"ESPI_CPU0_D3";
21"ESPI_CPU0_D2";
22"ESPI_CPU0_D1";
23"RST_ESPI_CPU0_RSTOUT_N";
24"PVDD18_S5_P0\g";
25"ESPI_CPU0_D0";
26"ESPI_CPU0_D3";
27"ESPI_CPU0_R_D2";
28"SCM_USB_OC_N";
29"SCM_USB_OC_BU_R_N";
30"SCM_USB_OC_BUF_N";
31"GND\g";
32"P1V8_AUX\g";
33"SPI_CPU0_D3";
34"SPI_CPU0_R_D3";
35"PVDD18_S5_P0\g";
36"RST_CPU0_KBRST_R_N";
37"CPU0_ESPI_CS0_N";
38"SPI_CPU0_R_CLK";
39"SPI_CPU0_CLK";
40"NC_CPU0_SPI_CS2_N";
41"SPI_CPU0_R_CS1_N";
42"SPI_CPU0_R_D2";
43"SPI_CPU0_R_D1";
44"SPI_CPU0_R_D0";
45"ESPI_CPU0_R_CS1_N";
46"ESPI_CPU0_CS1_N";
47"SPI_CPU0_CS1_N";
48"SPI_CPU0_CS0_N";
49"USB2_CPU0_P10_DN";
50"USB3_CPU0_BMC_RX_HUB_C_DP";
51"USB3_CPU0_BMC_RX_HUB_C_DN";
52"USB3_CPU0_BMC_TX_DP";
53"USB3_CPU0_BMC_TX_DN";
54"SCM_USB_OC_BUF_N";
55"USB2_CPU0_P11_DN";
56"USB2_CPU0_P10_DP";
57"USB2_CPU0_P1_DN";
58"USB2_CPU0_P1_DP";
59"USB2_CPU0_P0_DN";
60"USB2_CPU0_P0_DP";
61"USB2_CPU0_P11_DP";
62"SPI_CPU0_R_TPM_CS_N";
63"SPI_CPU0_D2";
64"SPI_CPU0_D0";
65"SPI_CPU0_R_CS0_N";
66"SPI_CPU0_D1";
%"UNIVERSAL_POWER"
"1","(-7925,3675)","0","pure_quanta_power","I277";
;
HDL_POWER"PVDD18_S5_P0"
CDS_LIB"pure_quanta_power";
"A"35;
%"Q_RES"
"2","(-7925,3225)","0","pure_quanta","I282";
;
LOCATION"R457"
$SEC"1"
CDS_SEC"1"
TOLERANCE"5%"
MATERIAL"EMPTY"
VALUE"4.7K"
WATTAGE"1/16W"
PACK_TYPE"0402LF"
CDS_LIB"pure_quanta"
PART_NUMBER"CS24702JB10";
"A"
$PN"1"35;
"B"
$PN"2"23;
%"Q_RES"
"2","(-8150,3250)","0","pure_quanta","I284";
;
LOCATION"R455"
$SEC"1"
CDS_SEC"1"
MATERIAL"EMPTY"
VALUE"4.7K"
PACK_TYPE"0402LF"
WATTAGE"1/16W"
TOLERANCE"5%"
CDS_LIB"pure_quanta"
PART_NUMBER"CS24702JB10";
"A"
$PN"1"35;
"B"
$PN"2"19;
%"GENOA_SP5"
"22","(-4675,4825)","0","pure_quanta","I287";
;
LOCATION"U25"
$SEC"22"
CDS_SEC"22"
MATERIAL"IO"
VALUE"SOCKET6096_13568-001"
PART_TYPE"SMLF"
NEEDS_NO_SIZE"TRUE"
CDS_LMAN_SYM_OUTLINE"-1100,1225,1100,-1225"
CDS_LIB"pure_quanta"
PART_NUMBER"DGA^6000030";
"ESPI_RSTOUT_L||AGPIO23"
$PN"DE27"9;
"ESPI_CLK1||SPI_CLK1||AGPIO75"
$PN"DG23"7;
"ESPI_CLK2||AGPIO74"
$PN"DF27"8;
"ESPI0_ALERT_L||AGPIO108"
$PN"DJ22"12;
"AGPIO76||SPI_TPM_CS_L"
$PN"DJ25"62;
"ESPI_CLK0||SPI_CLK0||AGPIO117"
$PN"DJ27"38;
"ESPI1_ALERT_L||AGPIO110"
$PN"DF24"13;
"ESPI_RSTIN_L||KBRST_L||AGPIO129"
$PN"DJ26"36;
"USB01_OC_L||AGPIO265"
$PN"E24"0;
"SPI_CS1_L||AGPIO119"
$PN"DG26"41;
"SPI_CS2_L||AGPIO126"
$PN"DH27"40;
"ESPI0_DAT0||SPI0_DAT0||AGPIO120"
$PN"DF28"44;
"ESPI0_DAT1||SPI0_DAT1||AGPIO121"
$PN"DG22"43;
"ESPI0_DAT2||SPI0_DAT2||AGPIO122"
$PN"DJ28"42;
"ESPI0_DAT3||SPI0_DAT3||AGPIO123"
$PN"DG29"34;
"ESPI1_DAT2||SPI1_DAT2||AGPIO133"
$PN"DF25"27;
"ESPI1_DAT3||SPI1_DAT3||AGPIO134"
$PN"DG25"14;
"ESPI_CS1_L||AGPIO125"
$PN"DJ23"45;
"ESPI1_DAT0||SPI1_DAT0||AGPIO131"
$PN"DH24"15;
"ESPI1_DAT1||SPI1_DAT1||AGPIO132"
$PN"DE24"16;
"SPI_CS0_L||AGPIO118"
$PN"DF30"65;
"USB00_OC_L||AGPIO264"
$PN"E23"54;
"ESPI_CS0_L||AGPIO124"
$PN"DG28"37;
"USB11_OC_L||AGPIO17"
$PN"DH40"0;
"USB10_OC_L||AGPIO16"
$PN"DG40"0;
"USB11_TXP"
$PN"DG58"0;
"USB11_TXN"
$PN"DH58"0;
"USB11_RXP"
$PN"DJ62"0;
"USB11_RXN"
$PN"DH62"0;
"USB11_DP"
$PN"DH60"61;
"USB11_DN"
$PN"DJ60"55;
"USB10_TXP"
$PN"DH69"0;
"USB10_TXN"
$PN"DJ69"0;
"USB10_RXP"
$PN"DJ65"0;
"USB10_RXN"
$PN"DH65"0;
"USB10_DP"
$PN"DJ67"56;
"USB10_DN"
$PN"DH67"49;
"USB01_TXP"
$PN"E30"0;
"USB01_TXN"
$PN"E29"0;
"USB01_RXP"
$PN"C29"0;
"USB01_RXN"
$PN"C28"0;
"USB01_DP"
$PN"A28"58;
"USB01_DN"
$PN"A29"57;
"USB00_TXP"
$PN"C25"52;
"USB00_TXN"
$PN"C26"53;
"USB00_RXP"
$PN"E27"50;
"USB00_RXN"
$PN"E26"51;
"USB00_DP"
$PN"A26"60;
"USB00_DN"
$PN"A25"59;
%"Q_RES"
"1","(-6950,4850)","0","pure_quanta","I327";
;
LOCATION"R470"
$SEC"1"
CDS_SEC"1"
VALUE"33"
PACK_TYPE"0402LF"
TOLERANCE"5%"
MATERIAL"CHIP"
WATTAGE"1/16W"
CDS_LIB"pure_quanta"
PART_NUMBER"CS03302JB10";
"B"
$PN"2"27;
"A"
$PN"1"5;
%"Q_RES"
"1","(-6950,4900)","0","pure_quanta","I328";
;
LOCATION"R469"
$SEC"1"
CDS_SEC"1"
VALUE"33"
PACK_TYPE"0402LF"
TOLERANCE"5%"
MATERIAL"CHIP"
WATTAGE"1/16W"
CDS_LIB"pure_quanta"
PART_NUMBER"CS03302JB10";
"B"
$PN"2"16;
"A"
$PN"1"4;
%"Q_RES"
"1","(-6950,4950)","0","pure_quanta","I329";
;
LOCATION"R468"
$SEC"1"
CDS_SEC"1"
VALUE"33"
PACK_TYPE"0402LF"
TOLERANCE"5%"
MATERIAL"CHIP"
WATTAGE"1/16W"
CDS_LIB"pure_quanta"
PART_NUMBER"CS03302JB10";
"B"
$PN"2"15;
"A"
$PN"1"3;
%"Q_RES"
"1","(-6950,4800)","0","pure_quanta","I330";
;
LOCATION"R471"
$SEC"1"
CDS_SEC"1"
VALUE"33"
PACK_TYPE"0402LF"
TOLERANCE"5%"
MATERIAL"CHIP"
WATTAGE"1/16W"
CDS_LIB"pure_quanta"
PART_NUMBER"CS03302JB10";
"B"
$PN"2"14;
"A"
$PN"1"26;
%"Q_RES"
"1","(-6950,4350)","0","pure_quanta","I332";
;
LOCATION"R474"
$SEC"1"
CDS_SEC"1"
VALUE"0"
CDS_LIB"pure_quanta"
WATTAGE"1/16W"
MATERIAL"CHIP"
TOLERANCE"5%"
PACK_TYPE"0402LF"
PART_NUMBER"CS00002JB13";
"B"
$PN"2"9;
"A"
$PN"1"10;
%"SN74LVC1G07DBVR"
"1","(-3375,2175)","0","pure_quanta","I373";
;
LOCATION"U3"
$SEC"1"
CDS_SEC"1"
MATERIAL"IC"
PACK_TYPE"SMLF"
VALUE"SN74LVC1G07DBVR"
NEEDS_NO_SIZE"TRUE"
CDS_LIB"pure_quanta"
PART_NUMBER"AL1G0007024";
"NC"
$PN"1"0;
"Y"
$PN"4"29;
"GND"
$PN"3"31;
"A"
$PN"2"28;
"VCC"
$PN"5"32;
%"Q_RES"
"1","(-2525,2175)","0","pure_quanta","I377";
;
LOCATION"R589"
$SEC"1"
CDS_SEC"1"
VALUE"0"
PACK_TYPE"0402LF"
TOLERANCE"5%"
MATERIAL"CHIP"
WATTAGE"1/16W"
CDS_LIB"pure_quanta"
PART_NUMBER"CS00002JB13";
"B"
$PN"2"30;
"A"
$PN"1"29;
%"Q_CAP"
"1","(-3725,2475)","2","pure_quanta","I379";
;
LOCATION"C30"
$SEC"1"
CDS_SEC"1"
MATERIAL"X7R"
PACK_TYPE"0402"
TOLERANCE"10%"
VALUE"0.1UF"
VOLTAGE"25V"
CDS_LIB"pure_quanta"
PART_NUMBER"CH4104K1B00";
"B"
$PN"2"1;
"A"
$PN"1"32;
%"UNIVERSAL_GND"
"1","(-3725,2275)","2","pure_quanta_power","I380";
;
CDS_LIB"pure_quanta_power"
HDL_POWER"GND";
"A"1;
%"UNIVERSAL_POWER"
"1","(-2350,2850)","0","pure_quanta_power","I382";
;
HDL_POWER"PVDD18_S5_P0"
CDS_LIB"pure_quanta_power";
"A"2;
%"Q_RES"
"2","(-2350,2575)","0","pure_quanta","I383";
;
LOCATION"R454"
$SEC"1"
CDS_SEC"1"
PACK_TYPE"0402LF"
TOLERANCE"5%"
MATERIAL"CHIP"
WATTAGE"1/16W"
VALUE"10K"
BOM_COST"I/O CONNECTOR"
CDS_LIB"pure_quanta"
PART_NUMBER"CS31002JB08";
"A"
$PN"1"2;
"B"
$PN"2"30;
%"UNIVERSAL_GND"
"1","(-3625,1950)","0","pure_quanta_power","I385";
;
HDL_POWER"GND"
CDS_LIB"pure_quanta_power";
"A"31;
%"VCC_CORE"
"1","(-3650,2750)","0","pure_quanta_power","I386";
;
HDL_POWER"P1V8_AUX"
CDS_LIB"pure_quanta_power";
"A"32;
%"UNIVERSAL_POWER"
"1","(-8125,2625)","0","pure_quanta_power","I395";
;
HDL_POWER"PVDD18_S5_P0"
CDS_LIB"pure_quanta_power";
"A"24;
%"Q_RES"
"1","(-7750,2375)","0","pure_quanta","I396";
;
LOCATION"R1503"
$SEC"1"
CDS_SEC"1"
MATERIAL"CHIP"
VALUE"30K"
PACK_TYPE"0402LF"
TOLERANCE"1%"
WATTAGE"1/16W"
CDS_LIB"pure_quanta"
PART_NUMBER"CS33002FB02";
"B"
$PN"2"25;
"A"
$PN"1"24;
%"Q_RES"
"1","(-7750,2325)","0","pure_quanta","I397";
;
LOCATION"R1504"
$SEC"1"
CDS_SEC"1"
VALUE"30K"
MATERIAL"CHIP"
CDS_LIB"pure_quanta"
WATTAGE"1/16W"
TOLERANCE"1%"
PACK_TYPE"0402LF"
PART_NUMBER"CS33002FB02";
"B"
$PN"2"22;
"A"
$PN"1"24;
%"Q_RES"
"1","(-7750,2275)","0","pure_quanta","I398";
;
LOCATION"R1505"
$SEC"1"
CDS_SEC"1"
MATERIAL"CHIP"
VALUE"30K"
CDS_LIB"pure_quanta"
WATTAGE"1/16W"
TOLERANCE"1%"
PACK_TYPE"0402LF"
PART_NUMBER"CS33002FB02";
"B"
$PN"2"21;
"A"
$PN"1"24;
%"Q_RES"
"1","(-7750,2225)","0","pure_quanta","I399";
;
LOCATION"R1506"
$SEC"1"
CDS_SEC"1"
VALUE"30K"
MATERIAL"CHIP"
CDS_LIB"pure_quanta"
WATTAGE"1/16W"
TOLERANCE"1%"
PACK_TYPE"0402LF"
PART_NUMBER"CS33002FB02";
"B"
$PN"2"20;
"A"
$PN"1"24;
%"Q_RES"
"1","(-7750,2150)","0","pure_quanta","I405";
;
LOCATION"R458"
$SEC"1"
CDS_SEC"1"
MATERIAL"EMPTY"
VALUE"30K"
PACK_TYPE"0402LF"
TOLERANCE"1%"
WATTAGE"1/16W"
CDS_LIB"pure_quanta"
PART_NUMBER"CS33002FB02";
"B"
$PN"2"18;
"A"
$PN"1"24;
%"Q_RES"
"1","(-6950,5900)","0","pure_quanta","I407";
;
LOCATION"R459"
$SEC"1"
CDS_SEC"1"
VALUE"33"
PACK_TYPE"0402LF"
TOLERANCE"5%"
MATERIAL"CHIP"
WATTAGE"1/16W"
CDS_LIB"pure_quanta"
PART_NUMBER"CS03302JB10";
"B"
$PN"2"65;
"A"
$PN"1"48;
%"Q_RES"
"1","(-6950,5850)","0","pure_quanta","I408";
;
LOCATION"R460"
$SEC"1"
CDS_SEC"1"
VALUE"33"
WATTAGE"1/16W"
MATERIAL"CHIP"
TOLERANCE"5%"
PACK_TYPE"0402LF"
CDS_LIB"pure_quanta"
PART_NUMBER"CS03302JB10";
"B"
$PN"2"41;
"A"
$PN"1"47;
%"Q_RES"
"1","(-6950,5650)","0","pure_quanta","I409";
;
LOCATION"R461"
$SEC"1"
CDS_SEC"1"
VALUE"33"
PACK_TYPE"0402LF"
TOLERANCE"5%"
MATERIAL"CHIP"
WATTAGE"1/16W"
CDS_LIB"pure_quanta"
PART_NUMBER"CS03302JB10";
"B"
$PN"2"38;
"A"
$PN"1"39;
%"Q_RES"
"1","(-6950,5250)","0","pure_quanta","I410";
;
LOCATION"R464"
$SEC"1"
CDS_SEC"1"
VALUE"33"
PACK_TYPE"0402LF"
TOLERANCE"5%"
MATERIAL"CHIP"
WATTAGE"1/16W"
CDS_LIB"pure_quanta"
PART_NUMBER"CS03302JB10";
"B"
$PN"2"44;
"A"
$PN"1"64;
%"Q_RES"
"1","(-6950,5200)","0","pure_quanta","I411";
;
LOCATION"R465"
$SEC"1"
CDS_SEC"1"
VALUE"49.9"
TOLERANCE"1%"
PACK_TYPE"0402LF"
MATERIAL"CHIP"
WATTAGE"1/16W"
CDS_LIB"pure_quanta"
PART_NUMBER"CS04992FB07";
"B"
$PN"2"43;
"A"
$PN"1"66;
%"Q_RES"
"1","(-6950,5150)","0","pure_quanta","I412";
;
LOCATION"R466"
$SEC"1"
CDS_SEC"1"
VALUE"33"
PACK_TYPE"0402LF"
TOLERANCE"5%"
MATERIAL"CHIP"
WATTAGE"1/16W"
CDS_LIB"pure_quanta"
PART_NUMBER"CS03302JB10";
"B"
$PN"2"42;
"A"
$PN"1"63;
%"Q_RES"
"1","(-6950,5100)","0","pure_quanta","I413";
;
LOCATION"R467"
$SEC"1"
CDS_SEC"1"
VALUE"33"
PACK_TYPE"0402LF"
TOLERANCE"5%"
MATERIAL"CHIP"
WATTAGE"1/16W"
CDS_LIB"pure_quanta"
PART_NUMBER"CS03302JB10";
"B"
$PN"2"34;
"A"
$PN"1"33;
%"Q_RES"
"1","(-6950,4250)","0","pure_quanta","I414";
;
LOCATION"R475"
$SEC"1"
CDS_SEC"1"
VALUE"33"
PACK_TYPE"0402LF"
TOLERANCE"5%"
MATERIAL"CHIP"
WATTAGE"1/16W"
CDS_LIB"pure_quanta"
PART_NUMBER"CS03302JB10";
"B"
$PN"2"62;
"A"
$PN"1"11;
%"Q_RES"
"1","(-6950,5550)","0","pure_quanta","I425";
;
LOCATION"R462"
$SEC"1"
CDS_SEC"1"
MATERIAL"EMPTY"
VALUE"33"
CDS_LIB"pure_quanta"
PACK_TYPE"0402LF"
TOLERANCE"5%"
WATTAGE"1/16W"
PART_NUMBER"CS03302JB10";
"B"
$PN"2"45;
"A"
$PN"1"46;
%"Q_RES"
"1","(-6950,5600)","0","pure_quanta","I426";
;
LOCATION"R1592"
$SEC"1"
CDS_SEC"1"
VALUE"33"
CDS_LIB"pure_quanta"
WATTAGE"1/16W"
MATERIAL"CHIP"
TOLERANCE"5%"
PACK_TYPE"0402LF"
PART_NUMBER"CS03302JB10";
"B"
$PN"2"37;
"A"
$PN"1"46;
%"Q_RES"
"1","(-6950,4500)","0","pure_quanta","I427";
;
LOCATION"R1593"
$SEC"1"
CDS_SEC"1"
VALUE"33"
CDS_LIB"pure_quanta"
WATTAGE"1/16W"
MATERIAL"CHIP"
TOLERANCE"5%"
PACK_TYPE"0402LF"
PART_NUMBER"CS03302JB10";
"B"
$PN"2"12;
"A"
$PN"1"17;
%"Q_RES"
"1","(-6950,4650)","0","pure_quanta","I428";
;
LOCATION"R472"
$SEC"1"
CDS_SEC"1"
VALUE"33"
MATERIAL"EMPTY"
WATTAGE"1/16W"
TOLERANCE"5%"
PACK_TYPE"0402LF"
CDS_LIB"pure_quanta"
PART_NUMBER"CS03302JB10";
"B"
$PN"2"13;
"A"
$PN"1"17;
%"Q_RES"
"1","(-6950,4450)","0","pure_quanta","I430";
;
LOCATION"R473"
$SEC"1"
CDS_SEC"1"
VALUE"0"
WATTAGE"1/16W"
MATERIAL"CHIP"
TOLERANCE"5%"
PACK_TYPE"0402LF"
CDS_LIB"pure_quanta"
PART_NUMBER"CS00002JB13";
"B"
$PN"2"7;
"A"
$PN"1"6;
END.
